FILE_TYPE = CONNECTIVITY;
{Allegro Design Entry HDL 17.2-2016 S081 (4005846) 1/11/2022}
"PAGE_NUMBER" = 163;
0"NC";
1"AGND_HSC\g";
2"HSC_VDD\g";
3"AGND_HSC\g";
4"AGND_HSC\g";
5"AGND_HSC\g";
6"HSC_VDD\g";
7"HSC_VDD_R_4";
8"HSC_ON";
9"HSC_OCREF";
10"HSC_SCREF";
11"HSC_CS_4";
12"HSC_MODE_4";
13"HSC_IMON";
14"HSC_SCREF_4";
15"HSC_VDD_R_3";
16"HSC_SCREF";
17"HSC_MODE_3";
18"HSC_SCREF_3";
19"HSC_SS";
20"HSC_NC1_4";
21"HSC_D_OC_4";
22"HSC_FLT_TYPE_4";
23"HSC_D_OC_R";
24"HSC_FLT_TYPE";
25"HSC_VTEMP";
26"HSC_FAULT";
27"HSC_SS";
28"HSC_NC1_3";
29"HSC_D_OC_3";
30"HSC_FLT_TYPE_3";
31"HSC_D_OC_R";
32"HSC_FLT_TYPE";
33"HSC_VTEMP";
34"HSC_FAULT";
35"HSC_IMON";
36"HSC_CS_3";
37"HSC_OCREF";
38"HSC_ON";
39"P12V_AUX\g";
40"P12V_AUX\g";
41"P12V_PSU\g";
42"AGND_HSC\g";
43"AGND_HSC\g";
44"P12V_PSU\g";
45"AGND_HSC\g";
46"AGND_HSC\g";
%"UNIVERSAL_GND"
"1","(-2700,-2250)","0","pure_quanta_power","I1";
;
HDL_POWER"AGND_HSC"
CDS_LIB"pure_quanta_power";
"A"46;
%"Q_RES"
"1","(-1900,-1125)","0","pure_quanta","I11";
;
LOCATION"PR3984"
$SEC"1"
CDS_SEC"1"
MATERIAL"CHIP"
VALUE"120K"
TOLERANCE"1%"
WATTAGE"1/16W"
PACK_TYPE"0402LF"
PART_NUMBER"CS41202FB05"
CDS_LIB"pure_quanta";
"B"
$PN"2"12;
"A"
$PN"1"45;
%"Q_CAP"
"1","(-1975,-1950)","0","pure_quanta","I12";
;
LOCATION"PC2349"
$SEC"1"
CDS_SEC"1"
PART_NUMBER"CH21006KB16"
PACK_TYPE"0402"
MATERIAL"EMPTY"
VOLTAGE"50V"
VALUE"1NF"
CDS_LIB"pure_quanta"
TOLERANCE"10%";
"B"
$PN"2"46;
"A"
$PN"1"9;
%"Q_RES"
"2","(-1475,-1950)","0","pure_quanta","I13";
;
LOCATION"PR3987"
$SEC"1"
CDS_SEC"1"
WATTAGE"1/16W"
TOLERANCE"0.1%"
MATERIAL"CHIP"
PART_NUMBER"CS22002BB07"
PACK_TYPE"0402LF"
VALUE"2K"
CDS_LIB"pure_quanta";
"A"
$PN"1"11;
"B"
$PN"2"46;
%"Q_RES"
"2","(-950,-1950)","0","pure_quanta","I14";
;
LOCATION"PR3991"
$SEC"1"
CDS_SEC"1"
WATTAGE"1/16W"
MATERIAL"CHIP"
PART_NUMBER"CS22002BB07"
PACK_TYPE"0402LF"
VALUE"2K"
TOLERANCE"0.1%"
CDS_LIB"pure_quanta";
"A"
$PN"1"13;
"B"
$PN"2"46;
%"Q_RES"
"1","(-1300,-1300)","0","pure_quanta","I16";
;
LOCATION"PR3989"
$SEC"1"
CDS_SEC"1"
WATTAGE"1/16W"
PART_NUMBER"CS00002JB13"
MATERIAL"CHIP"
TOLERANCE"5%"
PACK_TYPE"0402LF"
VALUE"0"
CDS_LIB"pure_quanta";
"B"
$PN"2"14;
"A"
$PN"1"10;
%"MP5991GLUZ"
"1","(25,-1200)","0","pure_quanta","I17";
;
LOCATION"PU297"
SEC"1"
VALUE"MP5991GLU-Z"
MATERIAL"IC"
PART_NUMBER"AL005991A00"
PART_TYPE"SMLF"
SEC_TYPE""
CDS_LIB"pure_quanta"
CDS_LMAN_SYM_OUTLINE"-325,775,325,-775"
NEEDS_NO_SIZE"TRUE";
"NC1"
$PN"7"20;
"FLT_TYPE"
$PN"6"22;
"SCREF_OCWREF"
$PN"17"14;
"MODE"
$PN"8"12;
"VOUT10"
$PN"32"40;
"VOUT9"
$PN"31"40;
"VOUT8"
$PN"30"40;
"VOUT7"
$PN"29"40;
"VOUT6"
$PN"28"40;
"VOUT5"
$PN"27"40;
"VIN9"
$PN"33"44;
"VIN8"
$PN"16"44;
"VIN7"
$PN"15"44;
"VIN6"
$PN"14"44;
"D_OC"
$PN"3"21;
"VOUT4"
$PN"26"40;
"VOUT3"
$PN"25"40;
"VOUT2"
$PN"2"40;
"VOUT1"
$PN"1"40;
"VTEMP"
$PN"18"25;
"GOK"
$PN"5"26;
"SS"
$PN"19"19;
"GND"
$PN"20"46;
"VDD33"
$PN"21"7;
"IMON"
$PN"22"13;
"CS"
$PN"23"11;
"OCREF"
$PN"24"9;
"ON"
$PN"4"8;
"VIN5"
$PN"13"44;
"VIN4"
$PN"12"44;
"VIN3"
$PN"11"44;
"VIN2"
$PN"10"44;
"VIN1"
$PN"9"44;
%"UNIVERSAL_POWER"
"1","(-950,-325)","0","pure_quanta_power","I18";
;
HDL_POWER"P12V_PSU"
ROOM"AUX_SW"
BOM_COST"MIO_VRD_SB"
CDS_LIB"pure_quanta_power";
"A"44;
%"UNIVERSAL_GND"
"1","(-3600,1175)","0","pure_quanta_power","I19";
;
HDL_POWER"AGND_HSC"
CDS_LIB"pure_quanta_power";
"A"1;
%"Q_CAP"
"1","(-2700,-1950)","0","pure_quanta","I2";
;
LOCATION"PC2225"
$SEC"1"
CDS_SEC"1"
VALUE"220PF"
PART_NUMBER"TMP_QCH12206KB14"
PACK_TYPE"0402"
MATERIAL"EMPTY"
VOLTAGE"50V"
TOLERANCE"10%"
CDS_LIB"pure_quanta";
"B"
$PN"2"46;
"A"
$PN"1"8;
%"Q_CAP"
"1","(-3600,1475)","0","pure_quanta","I20";
;
LOCATION"PC3272"
$SEC"1"
CDS_SEC"1"
VOLTAGE"25V"
PACK_TYPE"C0402"
MATERIAL"X6S"
PART_NUMBER"CH5104KEB02"
VALUE"1UF"
CDS_LIB"pure_quanta"
TOLERANCE"10%";
"B"
$PN"2"1;
"A"
$PN"1"15;
%"Q_RES"
"1","(-3600,1950)","1","pure_quanta","I21";
;
LOCATION"PR3980"
$SEC"1"
CDS_SEC"1"
MATERIAL"CHIP"
PART_NUMBER"CS00002JB13"
WATTAGE"1/16W"
PACK_TYPE"0402LF"
TOLERANCE"5%"
VALUE"0"
CDS_LIB"pure_quanta";
"B"
$PN"2"2;
"A"
$PN"1"15;
%"UNIVERSAL_GND"
"1","(-2700,525)","0","pure_quanta_power","I23";
;
HDL_POWER"AGND_HSC"
CDS_LIB"pure_quanta_power";
"A"43;
%"Q_CAP"
"1","(-2700,825)","0","pure_quanta","I24";
;
LOCATION"PC2224"
$SEC"1"
CDS_SEC"1"
VALUE"220PF"
MATERIAL"EMPTY"
PART_NUMBER"TMP_QCH12206KB14"
VOLTAGE"50V"
PACK_TYPE"0402"
TOLERANCE"10%"
CDS_LIB"pure_quanta";
"B"
$PN"2"43;
"A"
$PN"1"38;
%"UNIVERSAL_GND"
"1","(-2725,1575)","0","pure_quanta_power","I25";
;
HDL_POWER"AGND_HSC"
CDS_LIB"pure_quanta_power";
"A"42;
%"Q_RES"
"1","(-1900,1650)","0","pure_quanta","I28";
;
LOCATION"PR3982"
$SEC"1"
CDS_SEC"1"
MATERIAL"CHIP"
PACK_TYPE"0402LF"
TOLERANCE"1%"
VALUE"120K"
PART_NUMBER"CS41202FB05"
WATTAGE"1/16W"
CDS_LIB"pure_quanta";
"B"
$PN"2"17;
"A"
$PN"1"42;
%"UNIVERSAL_POWER"
"1","(-3600,2200)","0","pure_quanta_power","I29";
;
HDL_POWER"HSC_VDD"
ROOM"AUX_SW"
CDS_LIB"pure_quanta_power"
BOM_COST"MIO_VRD_SB";
"A"2;
%"UNIVERSAL_GND"
"1","(-3575,-1600)","0","pure_quanta_power","I3";
;
HDL_POWER"AGND_HSC"
CDS_LIB"pure_quanta_power";
"A"3;
%"Q_CAP"
"1","(-1950,825)","0","pure_quanta","I30";
;
LOCATION"PC2350"
$SEC"1"
CDS_SEC"1"
PART_NUMBER"CH21006KB16"
VALUE"1NF"
MATERIAL"EMPTY"
PACK_TYPE"0402"
VOLTAGE"50V"
CDS_LIB"pure_quanta"
TOLERANCE"10%";
"B"
$PN"2"43;
"A"
$PN"1"37;
%"Q_RES"
"2","(-1475,825)","0","pure_quanta","I31";
;
LOCATION"PR3986"
$SEC"1"
CDS_SEC"1"
PACK_TYPE"0402LF"
VALUE"2K"
TOLERANCE"0.1%"
PART_NUMBER"CS22002BB07"
WATTAGE"1/16W"
MATERIAL"CHIP"
CDS_LIB"pure_quanta";
"A"
$PN"1"36;
"B"
$PN"2"43;
%"Q_RES"
"1","(-1325,1475)","0","pure_quanta","I33";
;
LOCATION"PR3988"
$SEC"1"
CDS_SEC"1"
MATERIAL"CHIP"
PACK_TYPE"0402LF"
PART_NUMBER"CS00002JB13"
WATTAGE"1/16W"
TOLERANCE"5%"
VALUE"0"
CDS_LIB"pure_quanta";
"B"
$PN"2"18;
"A"
$PN"1"16;
%"Q_RES"
"2","(-950,825)","0","pure_quanta","I34";
;
LOCATION"PR3990"
$SEC"1"
CDS_SEC"1"
PART_NUMBER"CS22002BB07"
PACK_TYPE"0402LF"
MATERIAL"CHIP"
VALUE"2K"
WATTAGE"1/16W"
TOLERANCE"0.1%"
CDS_LIB"pure_quanta";
"A"
$PN"1"35;
"B"
$PN"2"43;
%"MP5991GLUZ"
"1","(25,1575)","0","pure_quanta","I35";
;
LOCATION"PU296"
SEC"1"
VALUE"MP5991GLU-Z"
MATERIAL"IC"
PART_NUMBER"AL005991A00"
PART_TYPE"SMLF"
SEC_TYPE""
NEEDS_NO_SIZE"TRUE"
CDS_LMAN_SYM_OUTLINE"-325,775,325,-775"
CDS_LIB"pure_quanta";
"NC1"
$PN"7"28;
"FLT_TYPE"
$PN"6"30;
"SCREF_OCWREF"
$PN"17"18;
"MODE"
$PN"8"17;
"VOUT10"
$PN"32"39;
"VOUT9"
$PN"31"39;
"VOUT8"
$PN"30"39;
"VOUT7"
$PN"29"39;
"VOUT6"
$PN"28"39;
"VOUT5"
$PN"27"39;
"VIN9"
$PN"33"41;
"VIN8"
$PN"16"41;
"VIN7"
$PN"15"41;
"VIN6"
$PN"14"41;
"D_OC"
$PN"3"29;
"VOUT4"
$PN"26"39;
"VOUT3"
$PN"25"39;
"VOUT2"
$PN"2"39;
"VOUT1"
$PN"1"39;
"VTEMP"
$PN"18"33;
"GOK"
$PN"5"34;
"SS"
$PN"19"27;
"GND"
$PN"20"43;
"VDD33"
$PN"21"15;
"IMON"
$PN"22"35;
"CS"
$PN"23"36;
"OCREF"
$PN"24"37;
"ON"
$PN"4"38;
"VIN5"
$PN"13"41;
"VIN4"
$PN"12"41;
"VIN3"
$PN"11"41;
"VIN2"
$PN"10"41;
"VIN1"
$PN"9"41;
%"UNIVERSAL_POWER"
"1","(-950,2450)","0","pure_quanta_power","I36";
;
HDL_POWER"P12V_PSU"
ROOM"AUX_SW"
BOM_COST"MIO_VRD_SB"
CDS_LIB"pure_quanta_power";
"A"41;
%"UNIVERSAL_GND"
"1","(1000,-2150)","0","pure_quanta_power","I37";
;
HDL_POWER"AGND_HSC"
CDS_LIB"pure_quanta_power";
"A"4;
%"Q_CAP"
"1","(1000,-1925)","0","pure_quanta","I38";
;
LOCATION"PC2227"
$SEC"1"
CDS_SEC"1"
VOLTAGE"16V"
MATERIAL"X7R"
PART_NUMBER"CH3683K1B09"
VALUE"0.068UF"
PACK_TYPE"0402"
CDS_LIB"pure_quanta"
TOLERANCE"10%";
"B"
$PN"2"4;
"A"
$PN"1"19;
%"Q_RES"
"1","(1500,-1375)","0","pure_quanta","I39";
;
LOCATION"PR3995"
$SEC"1"
CDS_SEC"1"
PART_NUMBER"CS00002JB13"
WATTAGE"1/16W"
VALUE"0"
TOLERANCE"5%"
MATERIAL"CHIP"
PACK_TYPE"0402LF"
CDS_LIB"pure_quanta";
"B"
$PN"2"24;
"A"
$PN"1"22;
%"Q_CAP"
"1","(-3575,-1300)","0","pure_quanta","I4";
;
LOCATION"PC2223"
$SEC"1"
CDS_SEC"1"
MATERIAL"X6S"
VOLTAGE"25V"
VALUE"1UF"
PART_NUMBER"CH5104KEB02"
PACK_TYPE"C0402"
TOLERANCE"10%"
CDS_LIB"pure_quanta";
"B"
$PN"2"3;
"A"
$PN"1"7;
%"Q_RES"
"1","(1500,-1200)","0","pure_quanta","I40";
;
LOCATION"PR3994"
$SEC"1"
CDS_SEC"1"
PART_NUMBER"CS00002JB13"
WATTAGE"1/16W"
PACK_TYPE"0402LF"
MATERIAL"CHIP"
TOLERANCE"5%"
VALUE"0"
CDS_LIB"pure_quanta";
"B"
$PN"2"23;
"A"
$PN"1"21;
%"UNIVERSAL_POWER"
"1","(1125,-325)","0","pure_quanta_power","I41";
;
HDL_POWER"P12V_AUX"
ROOM"AUX_SW"
BOM_COST"MIO_VRD_SB"
CDS_LIB"pure_quanta_power";
"A"40;
%"Q_CAP"
"1","(1000,850)","0","pure_quanta","I47";
;
LOCATION"PC2226"
$SEC"1"
CDS_SEC"1"
MATERIAL"X7R"
PART_NUMBER"CH3683K1B09"
PACK_TYPE"0402"
VALUE"0.068UF"
VOLTAGE"16V"
CDS_LIB"pure_quanta"
TOLERANCE"10%";
"B"
$PN"2"5;
"A"
$PN"1"27;
%"UNIVERSAL_GND"
"1","(1000,625)","0","pure_quanta_power","I48";
;
HDL_POWER"AGND_HSC"
CDS_LIB"pure_quanta_power";
"A"5;
%"Q_RES"
"1","(1500,1400)","0","pure_quanta","I49";
;
LOCATION"PR3993"
$SEC"1"
CDS_SEC"1"
PART_NUMBER"CS00002JB13"
PACK_TYPE"0402LF"
VALUE"0"
MATERIAL"CHIP"
TOLERANCE"5%"
WATTAGE"1/16W"
CDS_LIB"pure_quanta";
"B"
$PN"2"32;
"A"
$PN"1"30;
%"Q_RES"
"1","(1500,1575)","0","pure_quanta","I50";
;
LOCATION"PR3992"
$SEC"1"
CDS_SEC"1"
WATTAGE"1/16W"
PART_NUMBER"CS00002JB13"
TOLERANCE"5%"
MATERIAL"CHIP"
PACK_TYPE"0402LF"
VALUE"0"
CDS_LIB"pure_quanta";
"B"
$PN"2"31;
"A"
$PN"1"29;
%"UNIVERSAL_POWER"
"1","(1125,2450)","0","pure_quanta_power","I51";
;
HDL_POWER"P12V_AUX"
ROOM"AUX_SW"
BOM_COST"MIO_VRD_SB"
CDS_LIB"pure_quanta_power";
"A"39;
%"Q_RES"
"1","(-3575,-825)","1","pure_quanta","I6";
;
LOCATION"PR3981"
$SEC"1"
CDS_SEC"1"
MATERIAL"CHIP"
TOLERANCE"5%"
WATTAGE"1/16W"
PART_NUMBER"CS00002JB13"
PACK_TYPE"0402LF"
VALUE"0"
CDS_LIB"pure_quanta";
"B"
$PN"2"6;
"A"
$PN"1"7;
%"UNIVERSAL_POWER"
"1","(-3575,-575)","0","pure_quanta_power","I7";
;
HDL_POWER"HSC_VDD"
ROOM"AUX_SW"
BOM_COST"MIO_VRD_SB"
CDS_LIB"pure_quanta_power";
"A"6;
%"UNIVERSAL_GND"
"1","(-2700,-1225)","0","pure_quanta_power","I8";
;
HDL_POWER"AGND_HSC"
CDS_LIB"pure_quanta_power";
"A"45;
END.
